# S9S_MB_2U (Grand Teton) — schematic netlist excerpt (pin names and nets, part order shuffled) for the footprints in the layout excerpt that follows; sources: Cadence DE-HDL packaged netlist, KiCad conversion of 03242023_DA0F0TMBIJ0_F0T_Motherboard_J_brd_V01_OCP.brd

R1198  Q_RES  10K 1% CHIP  pkg 0402LF  page 182 : A = P3V3_AUX ; B = PU_ACPRESENT
PC571_P1_1  Q_CAP  22UF 16V 20% X6S  pkg C0805  page 285 : A = SW_P12V_PVCCIN_CPU1_FLT ; B = GND
C624  Q_CAP  1UF 25V 10% EMPTY  pkg C0402  page 129 : A = RST_PLD_CPU0_DRAM_EF_N ; B = GND

(kicad_pcb
	(version 20260206)
	(generator "pcbnew")
	(generator_version "10.0")
	(general
		(thickness 1.6)
		(legacy_teardrops no)
	)
	(paper "A4")
	(title_block
		(title "03242023_DA0F0TMBIJ0_F0T_Motherboard_J_brd_V01_OCP.brd")
		(comment 1 "Grand Teton / footprints 4530-4532 of 6105")
	)
	(layers
		(0 "F.Cu" signal "TOP")
		(4 "In1.Cu" signal "GND")
		(6 "In2.Cu" signal "IN1")
		(8 "In3.Cu" signal "GND1")
		(10 "In4.Cu" signal "IN2")
		(12 "In5.Cu" signal "GND2")
		(14 "In6.Cu" signal "IN3")
		(16 "In7.Cu" signal "GND3")
		(18 "In8.Cu" signal "VCC")
		(20 "In9.Cu" signal "VCC1")
		(22 "In10.Cu" signal "GND4")
		(24 "In11.Cu" signal "IN4")
		(26 "In12.Cu" signal "GND5")
		(28 "In13.Cu" signal "IN5")
		(30 "In14.Cu" signal "GND6")
		(32 "In15.Cu" signal "IN6")
		(34 "In16.Cu" signal "GND7")
		(2 "B.Cu" signal "BOTTOM")
		(9 "F.Adhes" user "F.Adhesive")
		(11 "B.Adhes" user "B.Adhesive")
		(13 "F.Paste" user "Package Geometry/Pastemask Top")
		(15 "B.Paste" user "Package Geometry/Pastemask Bottom")
		(5 "F.SilkS" user "Ref Des/Silkscreen Top")
		(7 "B.SilkS" user "Ref Des/Silkscreen Bottom")
		(1 "F.Mask" user "Board Geometry/Soldermask Top")
		(3 "B.Mask" user "Board Geometry/Soldermask Bottom")
		(17 "Dwgs.User" user "User.Drawings")
		(19 "Cmts.User" user "User.Comments")
		(21 "Eco1.User" user "User.Eco1")
		(23 "Eco2.User" user "User.Eco2")
		(25 "Edge.Cuts" user "Board Geometry/Outline")
		(27 "Margin" user)
		(31 "F.CrtYd" user "Package Geometry/Place Bound Top")
		(29 "B.CrtYd" user "Package Geometry/Place Bound Bottom")
		(35 "F.Fab" user "Ref Des/Assembly Top")
		(33 "B.Fab" user "Ref Des/Assembly Bottom")
	)
	(footprint ""
		(layer "B.Cu")
		(at 312.189622 -29.708348 180)
		(property "Reference" "R1198"
			(at 0 0 0)
			(layer "B.SilkS")
			(hide yes)
			(effects
				(font
					(size 1.27 1.27)
				)
				(justify mirror)
			)
		)
		(property "Value" ""
			(at 0 0 0)
			(layer "B.Fab")
			(effects
				(font
					(size 1.27 1.27)
				)
				(justify mirror)
			)
		)
		(duplicate_pad_numbers_are_jumpers no)
		(fp_line
			(start 0.7874 0.4064)
			(end 0.7874 -0.4064)
			(stroke
				(width 0.1524)
				(type default)
			)
			(layer "B.SilkS")
		)
		(fp_line
			(start 0.7874 -0.4064)
			(end -0.7874 -0.4064)
			(stroke
				(width 0.1524)
				(type default)
			)
			(layer "B.SilkS")
		)
		(fp_line
			(start -0.7874 0.4064)
			(end 0.7874 0.4064)
			(stroke
				(width 0.1524)
				(type default)
			)
			(layer "B.SilkS")
		)
		(fp_line
			(start -0.7874 -0.4064)
			(end -0.7874 0.4064)
			(stroke
				(width 0.1524)
				(type default)
			)
			(layer "B.SilkS")
		)
		(fp_line
			(start 0.67945 0.3048)
			(end 0.67945 -0.305054)
			(stroke
				(width 0.1)
				(type default)
			)
			(layer "B.Fab")
		)
		(fp_line
			(start 0.67945 -0.305054)
			(end 0.12065 -0.305054)
			(stroke
				(width 0.1)
				(type default)
			)
			(layer "B.Fab")
		)
		(fp_line
			(start 0.12065 0.3048)
			(end 0.67945 0.3048)
			(stroke
				(width 0.1)
				(type default)
			)
			(layer "B.Fab")
		)
		(fp_line
			(start 0.12065 0.2794)
			(end 0.12065 0.3048)
			(stroke
				(width 0.1)
				(type default)
			)
			(layer "B.Fab")
		)
		(fp_line
			(start 0.12065 -0.2794)
			(end -0.12065 -0.2794)
			(stroke
				(width 0.1)
				(type default)
			)
			(layer "B.Fab")
		)
		(fp_line
			(start 0.12065 -0.305054)
			(end 0.12065 -0.2794)
			(stroke
				(width 0.1)
				(type default)
			)
			(layer "B.Fab")
		)
		(fp_line
			(start -0.120396 0.3048)
			(end -0.120396 0.2794)
			(stroke
				(width 0.1)
				(type default)
			)
			(layer "B.Fab")
		)
		(fp_line
			(start -0.120396 0.2794)
			(end 0.12065 0.2794)
			(stroke
				(width 0.1)
				(type default)
			)
			(layer "B.Fab")
		)
		(fp_line
			(start -0.12065 -0.2794)
			(end -0.12065 -0.3048)
			(stroke
				(width 0.1)
				(type default)
			)
			(layer "B.Fab")
		)
		(fp_line
			(start -0.12065 -0.3048)
			(end -0.67945 -0.3048)
			(stroke
				(width 0.1)
				(type default)
			)
			(layer "B.Fab")
		)
		(fp_line
			(start -0.67945 0.3048)
			(end -0.120396 0.3048)
			(stroke
				(width 0.1)
				(type default)
			)
			(layer "B.Fab")
		)
		(fp_line
			(start -0.67945 -0.3048)
			(end -0.67945 0.3048)
			(stroke
				(width 0.1)
				(type default)
			)
			(layer "B.Fab")
		)
		(pad "1" smd circle
			(at 0.40005 0)
			(size 0 0)
			(layers "B.Cu" "B.Mask" "B.Paste")
			(net "P3V3_AUX")
		)
		(pad "2" smd circle
			(at -0.40005 0)
			(size 0 0)
			(layers "B.Cu" "B.Mask" "B.Paste")
			(net "PU_ACPRESENT")
		)
	)
	(footprint ""
		(layer "B.Cu")
		(at 98.052382 -333.639922 90)
		(property "Reference" "PC571_P1_1"
			(at 0 0 90)
			(layer "B.SilkS")
			(hide yes)
			(effects
				(font
					(size 1.27 1.27)
				)
				(justify mirror)
			)
		)
		(property "Value" ""
			(at 0 0 90)
			(layer "B.Fab")
			(effects
				(font
					(size 1.27 1.27)
				)
				(justify mirror)
			)
		)
		(duplicate_pad_numbers_are_jumpers no)
		(fp_line
			(start 1.524 -0.762)
			(end -1.524 -0.762)
			(stroke
				(width 0.1524)
				(type default)
			)
			(layer "B.SilkS")
		)
		(fp_line
			(start -1.524 -0.762)
			(end -1.524 0.762)
			(stroke
				(width 0.1524)
				(type default)
			)
			(layer "B.SilkS")
		)
		(fp_line
			(start 1.524 0.762)
			(end 1.524 -0.762)
			(stroke
				(width 0.1524)
				(type default)
			)
			(layer "B.SilkS")
		)
		(fp_line
			(start -1.524 0.762)
			(end 1.524 0.762)
			(stroke
				(width 0.1524)
				(type default)
			)
			(layer "B.SilkS")
		)
		(fp_line
			(start 1.1049 -0.724916)
			(end 1.1049 0.724916)
			(stroke
				(width 0.1)
				(type default)
			)
			(layer "B.Fab")
		)
		(fp_line
			(start -1.1049 -0.724916)
			(end 1.1049 -0.724916)
			(stroke
				(width 0.1)
				(type default)
			)
			(layer "B.Fab")
		)
		(fp_line
			(start 1.1049 0.724916)
			(end -1.1049 0.724916)
			(stroke
				(width 0.1)
				(type default)
			)
			(layer "B.Fab")
		)
		(fp_line
			(start -1.1049 0.724916)
			(end -1.1049 -0.724916)
			(stroke
				(width 0.1)
				(type default)
			)
			(layer "B.Fab")
		)
		(pad "1" smd rect
			(at 0.889 0 90)
			(size 1.016 1.27)
			(layers "B.Cu" "B.Mask" "B.Paste")
			(net "SW_P12V_PVCCIN_CPU1_FLT")
		)
		(pad "2" smd rect
			(at -0.889 0 90)
			(size 1.016 1.27)
			(layers "B.Cu" "B.Mask" "B.Paste")
			(net "GND")
		)
	)
	(footprint ""
		(layer "B.Cu")
		(at 421.304466 -193.353436 -90)
		(property "Reference" "C624"
			(at 0 0 90)
			(layer "B.SilkS")
			(hide yes)
			(effects
				(font
					(size 1.27 1.27)
				)
				(justify mirror)
			)
		)
		(property "Value" ""
			(at 0 0 90)
			(layer "B.Fab")
			(effects
				(font
					(size 1.27 1.27)
				)
				(justify mirror)
			)
		)
		(duplicate_pad_numbers_are_jumpers no)
		(fp_line
			(start -0.7874 0.4064)
			(end 0.7874 0.4064)
			(stroke
				(width 0.1524)
				(type default)
			)
			(layer "B.SilkS")
		)
		(fp_line
			(start 0.7874 0.4064)
			(end 0.7874 -0.4064)
			(stroke
				(width 0.1524)
				(type default)
			)
			(layer "B.SilkS")
		)
		(fp_line
			(start -0.7874 -0.4064)
			(end -0.7874 0.4064)
			(stroke
				(width 0.1524)
				(type default)
			)
			(layer "B.SilkS")
		)
		(fp_line
			(start 0.7874 -0.4064)
			(end -0.7874 -0.4064)
			(stroke
				(width 0.1524)
				(type default)
			)
			(layer "B.SilkS")
		)
		(fp_line
			(start -0.67945 0.3048)
			(end -0.120396 0.3048)
			(stroke
				(width 0.1)
				(type default)
			)
			(layer "B.Fab")
		)
		(fp_line
			(start -0.120396 0.3048)
			(end -0.120396 0.2794)
			(stroke
				(width 0.1)
				(type default)
			)
			(layer "B.Fab")
		)
		(fp_line
			(start 0.12065 0.3048)
			(end 0.67945 0.3048)
			(stroke
				(width 0.1)
				(type default)
			)
			(layer "B.Fab")
		)
		(fp_line
			(start 0.67945 0.3048)
			(end 0.67945 -0.305054)
			(stroke
				(width 0.1)
				(type default)
			)
			(layer "B.Fab")
		)
		(fp_line
			(start -0.120396 0.2794)
			(end 0.12065 0.2794)
			(stroke
				(width 0.1)
				(type default)
			)
			(layer "B.Fab")
		)
		(fp_line
			(start 0.12065 0.2794)
			(end 0.12065 0.3048)
			(stroke
				(width 0.1)
				(type default)
			)
			(layer "B.Fab")
		)
		(fp_line
			(start -0.12065 -0.2794)
			(end -0.12065 -0.3048)
			(stroke
				(width 0.1)
				(type default)
			)
			(layer "B.Fab")
		)
		(fp_line
			(start 0.12065 -0.2794)
			(end -0.12065 -0.2794)
			(stroke
				(width 0.1)
				(type default)
			)
			(layer "B.Fab")
		)
		(fp_line
			(start -0.67945 -0.3048)
			(end -0.67945 0.3048)
			(stroke
				(width 0.1)
				(type default)
			)
			(layer "B.Fab")
		)
		(fp_line
			(start -0.12065 -0.3048)
			(end -0.67945 -0.3048)
			(stroke
				(width 0.1)
				(type default)
			)
			(layer "B.Fab")
		)
		(fp_line
			(start 0.12065 -0.305054)
			(end 0.12065 -0.2794)
			(stroke
				(width 0.1)
				(type default)
			)
			(layer "B.Fab")
		)
		(fp_line
			(start 0.67945 -0.305054)
			(end 0.12065 -0.305054)
			(stroke
				(width 0.1)
				(type default)
			)
			(layer "B.Fab")
		)
		(pad "1" smd circle
			(at 0.40005 0 90)
			(size 0 0)
			(layers "B.Cu" "B.Mask" "B.Paste")
			(net "RST_PLD_CPU0_DRAM_EF_N")
		)
		(pad "2" smd circle
			(at -0.40005 0 90)
			(size 0 0)
			(layers "B.Cu" "B.Mask" "B.Paste")
			(net "GND")
		)
	)
)
